FILE_TYPE = CONNECTIVITY;
{Allegro Design Entry HDL 17.2-2016 S081 (4005846) 1/11/2022}
"PAGE_NUMBER" = 118;
0"NC";
END.
